# SCM (Grand Teton) — schematic netlist excerpt (pin names and nets, part order shuffled) for the footprints in the layout excerpt that follows; sources: Cadence DE-HDL packaged netlist, KiCad conversion of 12092022_DA0F0TMDCD0_F0T_Management_Board_D_brd_V3_OCP.brd

R137  Q_RES  33.2 1% CHIP  pkg 0402LF  page 12 : A = SMB_BMC_MM12_R_SCL ; B = SMB_BMC_MM12_SCL
R426  Q_RES  33.2 1% CHIP  pkg 0402LF  page 12 : A = SMB_BMC_MM14_R_SDA ; B = SMB_BMC_MM14_SDA

(kicad_pcb
	(version 20260206)
	(generator "pcbnew")
	(generator_version "10.0")
	(general
		(thickness 1.6)
		(legacy_teardrops no)
	)
	(paper "A4")
	(title_block
		(title "12092022_DA0F0TMDCD0_F0T_Management_Board_D_brd_V3_OCP.brd")
		(comment 1 "Grand Teton / footprints 653-654 of 1440")
	)
	(layers
		(0 "F.Cu" signal "TOP")
		(4 "In1.Cu" signal "GND")
		(6 "In2.Cu" signal "IN1")
		(8 "In3.Cu" signal "GND1")
		(10 "In4.Cu" signal "IN2")
		(12 "In5.Cu" signal "VCC")
		(14 "In6.Cu" signal "VCC1")
		(16 "In7.Cu" signal "IN3")
		(18 "In8.Cu" signal "GND2")
		(20 "In9.Cu" signal "IN4")
		(22 "In10.Cu" signal "GND3")
		(2 "B.Cu" signal "BOTTOM")
		(9 "F.Adhes" user "F.Adhesive")
		(11 "B.Adhes" user "B.Adhesive")
		(13 "F.Paste" user "Package Geometry/Pastemask Top")
		(15 "B.Paste" user "Package Geometry/Pastemask Bottom")
		(5 "F.SilkS" user "Ref Des/Silkscreen Top")
		(7 "B.SilkS" user "Ref Des/Silkscreen Bottom")
		(1 "F.Mask" user "Board Geometry/Soldermask Top")
		(3 "B.Mask" user "Board Geometry/Soldermask Bottom")
		(17 "Dwgs.User" user "User.Drawings")
		(19 "Cmts.User" user "User.Comments")
		(21 "Eco1.User" user "User.Eco1")
		(23 "Eco2.User" user "User.Eco2")
		(25 "Edge.Cuts" user "Board Geometry/Outline")
		(27 "Margin" user)
		(31 "F.CrtYd" user "Package Geometry/Place Bound Top")
		(29 "B.CrtYd" user "Package Geometry/Place Bound Bottom")
		(35 "F.Fab" user "Ref Des/Assembly Top")
		(33 "B.Fab" user "Ref Des/Assembly Bottom")
	)
	(footprint ""
		(layer "F.Cu")
		(at 39.9415 -47.587916 180)
		(property "Reference" "R137"
			(at 0 0 180)
			(layer "F.SilkS")
			(hide yes)
			(effects
				(font
					(size 1.27 1.27)
				)
			)
		)
		(property "Value" ""
			(at 0 0 180)
			(layer "F.Fab")
			(effects
				(font
					(size 1.27 1.27)
				)
			)
		)
		(duplicate_pad_numbers_are_jumpers no)
		(fp_line
			(start 0.7874 0.4064)
			(end -0.7874 0.4064)
			(stroke
				(width 0.1524)
				(type default)
			)
			(layer "F.SilkS")
		)
		(fp_line
			(start 0.7874 -0.4064)
			(end 0.7874 0.4064)
			(stroke
				(width 0.1524)
				(type default)
			)
			(layer "F.SilkS")
		)
		(fp_line
			(start -0.7874 0.4064)
			(end -0.7874 -0.4064)
			(stroke
				(width 0.1524)
				(type default)
			)
			(layer "F.SilkS")
		)
		(fp_line
			(start -0.7874 -0.4064)
			(end 0.7874 -0.4064)
			(stroke
				(width 0.1524)
				(type default)
			)
			(layer "F.SilkS")
		)
		(fp_line
			(start 0.67945 0.3048)
			(end 0.120396 0.3048)
			(stroke
				(width 0.1)
				(type default)
			)
			(layer "F.Fab")
		)
		(fp_line
			(start 0.67945 -0.3048)
			(end 0.67945 0.3048)
			(stroke
				(width 0.1)
				(type default)
			)
			(layer "F.Fab")
		)
		(fp_line
			(start 0.12065 -0.2794)
			(end 0.12065 -0.3048)
			(stroke
				(width 0.1)
				(type default)
			)
			(layer "F.Fab")
		)
		(fp_line
			(start 0.12065 -0.3048)
			(end 0.67945 -0.3048)
			(stroke
				(width 0.1)
				(type default)
			)
			(layer "F.Fab")
		)
		(fp_line
			(start 0.120396 0.3048)
			(end 0.120396 0.2794)
			(stroke
				(width 0.1)
				(type default)
			)
			(layer "F.Fab")
		)
		(fp_line
			(start 0.120396 0.2794)
			(end -0.12065 0.2794)
			(stroke
				(width 0.1)
				(type default)
			)
			(layer "F.Fab")
		)
		(fp_line
			(start -0.12065 0.3048)
			(end -0.67945 0.3048)
			(stroke
				(width 0.1)
				(type default)
			)
			(layer "F.Fab")
		)
		(fp_line
			(start -0.12065 0.2794)
			(end -0.12065 0.3048)
			(stroke
				(width 0.1)
				(type default)
			)
			(layer "F.Fab")
		)
		(fp_line
			(start -0.12065 -0.2794)
			(end 0.12065 -0.2794)
			(stroke
				(width 0.1)
				(type default)
			)
			(layer "F.Fab")
		)
		(fp_line
			(start -0.12065 -0.305054)
			(end -0.12065 -0.2794)
			(stroke
				(width 0.1)
				(type default)
			)
			(layer "F.Fab")
		)
		(fp_line
			(start -0.67945 0.3048)
			(end -0.67945 -0.305054)
			(stroke
				(width 0.1)
				(type default)
			)
			(layer "F.Fab")
		)
		(fp_line
			(start -0.67945 -0.305054)
			(end -0.12065 -0.305054)
			(stroke
				(width 0.1)
				(type default)
			)
			(layer "F.Fab")
		)
		(pad "1" smd circle
			(at -0.40005 0 180)
			(size 0 0)
			(layers "F.Cu" "F.Mask" "F.Paste")
			(net "SMB_BMC_MM12_R_SCL")
		)
		(pad "2" smd circle
			(at 0.40005 0 180)
			(size 0 0)
			(layers "F.Cu" "F.Mask" "F.Paste")
			(net "SMB_BMC_MM12_SCL")
		)
	)
	(footprint ""
		(layer "F.Cu")
		(at 39.9288 -44.3992 180)
		(property "Reference" "R426"
			(at 0 0 180)
			(layer "F.SilkS")
			(hide yes)
			(effects
				(font
					(size 1.27 1.27)
				)
			)
		)
		(property "Value" ""
			(at 0 0 180)
			(layer "F.Fab")
			(effects
				(font
					(size 1.27 1.27)
				)
			)
		)
		(duplicate_pad_numbers_are_jumpers no)
		(fp_line
			(start 0.7874 0.4064)
			(end -0.7874 0.4064)
			(stroke
				(width 0.1524)
				(type default)
			)
			(layer "F.SilkS")
		)
		(fp_line
			(start 0.7874 -0.4064)
			(end 0.7874 0.4064)
			(stroke
				(width 0.1524)
				(type default)
			)
			(layer "F.SilkS")
		)
		(fp_line
			(start -0.7874 0.4064)
			(end -0.7874 -0.4064)
			(stroke
				(width 0.1524)
				(type default)
			)
			(layer "F.SilkS")
		)
		(fp_line
			(start -0.7874 -0.4064)
			(end 0.7874 -0.4064)
			(stroke
				(width 0.1524)
				(type default)
			)
			(layer "F.SilkS")
		)
		(fp_line
			(start 0.67945 0.3048)
			(end 0.120396 0.3048)
			(stroke
				(width 0.1)
				(type default)
			)
			(layer "F.Fab")
		)
		(fp_line
			(start 0.67945 -0.3048)
			(end 0.67945 0.3048)
			(stroke
				(width 0.1)
				(type default)
			)
			(layer "F.Fab")
		)
		(fp_line
			(start 0.12065 -0.2794)
			(end 0.12065 -0.3048)
			(stroke
				(width 0.1)
				(type default)
			)
			(layer "F.Fab")
		)
		(fp_line
			(start 0.12065 -0.3048)
			(end 0.67945 -0.3048)
			(stroke
				(width 0.1)
				(type default)
			)
			(layer "F.Fab")
		)
		(fp_line
			(start 0.120396 0.3048)
			(end 0.120396 0.2794)
			(stroke
				(width 0.1)
				(type default)
			)
			(layer "F.Fab")
		)
		(fp_line
			(start 0.120396 0.2794)
			(end -0.12065 0.2794)
			(stroke
				(width 0.1)
				(type default)
			)
			(layer "F.Fab")
		)
		(fp_line
			(start -0.12065 0.3048)
			(end -0.67945 0.3048)
			(stroke
				(width 0.1)
				(type default)
			)
			(layer "F.Fab")
		)
		(fp_line
			(start -0.12065 0.2794)
			(end -0.12065 0.3048)
			(stroke
				(width 0.1)
				(type default)
			)
			(layer "F.Fab")
		)
		(fp_line
			(start -0.12065 -0.2794)
			(end 0.12065 -0.2794)
			(stroke
				(width 0.1)
				(type default)
			)
			(layer "F.Fab")
		)
		(fp_line
			(start -0.12065 -0.305054)
			(end -0.12065 -0.2794)
			(stroke
				(width 0.1)
				(type default)
			)
			(layer "F.Fab")
		)
		(fp_line
			(start -0.67945 0.3048)
			(end -0.67945 -0.305054)
			(stroke
				(width 0.1)
				(type default)
			)
			(layer "F.Fab")
		)
		(fp_line
			(start -0.67945 -0.305054)
			(end -0.12065 -0.305054)
			(stroke
				(width 0.1)
				(type default)
			)
			(layer "F.Fab")
		)
		(pad "1" smd circle
			(at -0.40005 0 180)
			(size 0 0)
			(layers "F.Cu" "F.Mask" "F.Paste")
			(net "SMB_BMC_MM14_R_SDA")
		)
		(pad "2" smd circle
			(at 0.40005 0 180)
			(size 0 0)
			(layers "F.Cu" "F.Mask" "F.Paste")
			(net "SMB_BMC_MM14_SDA")
		)
	)
)
